# S9S_MB_2U (Grand Teton) — schematic netlist excerpt (pin names and nets, part order shuffled) for the footprints in the layout excerpt that follows; sources: Cadence DE-HDL packaged netlist, KiCad conversion of 03242023_DA0F0TMBIJ0_F0T_Motherboard_J_brd_V01_OCP.brd

X9  TP_TDR_4P_FTS  TP_TDR_4P_DIP EMPTY  pkg TH  page 309
  S1  = TDR_DIFF_85_IN2_DN
  P1  = T1_GND
  P2  = T1_GND
  S2  = TDR_DIFF_85_IN2_DP

PR3944  Q_RES  46.4K 1% CHIP  pkg 0402LF  page 193 : A = P12V_E1S_ISET_0 ; B = GND

(kicad_pcb
	(version 20260206)
	(generator "pcbnew")
	(generator_version "10.0")
	(general
		(thickness 1.6)
		(legacy_teardrops no)
	)
	(paper "A4")
	(title_block
		(title "03242023_DA0F0TMBIJ0_F0T_Motherboard_J_brd_V01_OCP.brd")
		(comment 1 "Grand Teton / footprints 875-876 of 6105")
	)
	(layers
		(0 "F.Cu" signal "TOP")
		(4 "In1.Cu" signal "GND")
		(6 "In2.Cu" signal "IN1")
		(8 "In3.Cu" signal "GND1")
		(10 "In4.Cu" signal "IN2")
		(12 "In5.Cu" signal "GND2")
		(14 "In6.Cu" signal "IN3")
		(16 "In7.Cu" signal "GND3")
		(18 "In8.Cu" signal "VCC")
		(20 "In9.Cu" signal "VCC1")
		(22 "In10.Cu" signal "GND4")
		(24 "In11.Cu" signal "IN4")
		(26 "In12.Cu" signal "GND5")
		(28 "In13.Cu" signal "IN5")
		(30 "In14.Cu" signal "GND6")
		(32 "In15.Cu" signal "IN6")
		(34 "In16.Cu" signal "GND7")
		(2 "B.Cu" signal "BOTTOM")
		(9 "F.Adhes" user "F.Adhesive")
		(11 "B.Adhes" user "B.Adhesive")
		(13 "F.Paste" user "Package Geometry/Pastemask Top")
		(15 "B.Paste" user "Package Geometry/Pastemask Bottom")
		(5 "F.SilkS" user "Ref Des/Silkscreen Top")
		(7 "B.SilkS" user "Ref Des/Silkscreen Bottom")
		(1 "F.Mask" user "Board Geometry/Soldermask Top")
		(3 "B.Mask" user "Board Geometry/Soldermask Bottom")
		(17 "Dwgs.User" user "User.Drawings")
		(19 "Cmts.User" user "User.Comments")
		(21 "Eco1.User" user "User.Eco1")
		(23 "Eco2.User" user "User.Eco2")
		(25 "Edge.Cuts" user "Board Geometry/Outline")
		(27 "Margin" user)
		(31 "F.CrtYd" user "Package Geometry/Place Bound Top")
		(29 "B.CrtYd" user "Package Geometry/Place Bound Bottom")
		(35 "F.Fab" user "Ref Des/Assembly Top")
		(33 "B.Fab" user "Ref Des/Assembly Bottom")
	)
	(footprint ""
		(layer "F.Cu")
		(at 506.598428 -153.16708 -90)
		(property "Reference" "X9"
			(at -1.373124 2.750058 90)
			(unlocked yes)
			(layer "F.SilkS")
			(effects
				(font
					(size 0.7874 0.5842)
					(thickness 0.1524)
				)
				(justify left)
			)
		)
		(property "Value" ""
			(at 0 0 270)
			(layer "F.Fab")
			(effects
				(font
					(size 1.27 1.27)
				)
			)
		)
		(property "Device Type" "TP_TDR_4P_FTS_MPKT4_H025P0200_I"
			(at 1.30175 1.27 0)
			(unlocked yes)
			(layer "F.Fab")
			(hide yes)
			(effects
				(font
					(size 0.635 0.4064)
					(thickness 0.1524)
				)
			)
		)
		(property "User Part Number" "TP15"
			(at 1.30175 1.27 0)
			(unlocked yes)
			(layer "Cmts.User")
			(hide yes)
			(effects
				(font
					(size 0.635 0.4064)
					(thickness 0.1524)
				)
			)
		)
		(duplicate_pad_numbers_are_jumpers no)
		(fp_line
			(start 0 3.81)
			(end 2.54 3.81)
			(stroke
				(width 0.1524)
				(type default)
			)
			(layer "F.SilkS")
		)
		(fp_line
			(start 2.54 3.81)
			(end 2.54 3.6703)
			(stroke
				(width 0.1524)
				(type default)
			)
			(layer "F.SilkS")
		)
		(fp_line
			(start 0 3.175)
			(end 0 3.81)
			(stroke
				(width 0.1524)
				(type default)
			)
			(layer "F.SilkS")
		)
		(fp_line
			(start 2.54 1.4097)
			(end 2.54 1.1303)
			(stroke
				(width 0.1524)
				(type default)
			)
			(layer "F.SilkS")
		)
		(fp_line
			(start 0 0.635)
			(end 0 1.905)
			(stroke
				(width 0.1524)
				(type default)
			)
			(layer "F.SilkS")
		)
		(fp_line
			(start 2.54 -1.1303)
			(end 2.54 -1.27)
			(stroke
				(width 0.1524)
				(type default)
			)
			(layer "F.SilkS")
		)
		(fp_line
			(start 0 -1.27)
			(end 0 -0.635)
			(stroke
				(width 0.1524)
				(type default)
			)
			(layer "F.SilkS")
		)
		(fp_line
			(start 2.54 -1.27)
			(end 0 -1.27)
			(stroke
				(width 0.1524)
				(type default)
			)
			(layer "F.SilkS")
		)
		(fp_poly
			(pts
				(xy -1.244346 0) (xy -2.768346 0.762) (xy -2.768346 -0.762)
			)
			(stroke
				(width 0)
				(type default)
			)
			(fill yes)
			(layer "F.SilkS")
		)
		(fp_line
			(start 0 3.81)
			(end 2.54 3.81)
			(stroke
				(width 0.1)
				(type default)
			)
			(layer "F.Fab")
		)
		(fp_line
			(start 2.54 3.81)
			(end 2.54 -1.27)
			(stroke
				(width 0.1)
				(type default)
			)
			(layer "F.Fab")
		)
		(fp_line
			(start 0 -1.27)
			(end 0 3.81)
			(stroke
				(width 0.1)
				(type default)
			)
			(layer "F.Fab")
		)
		(fp_line
			(start 2.54 -1.27)
			(end 0 -1.27)
			(stroke
				(width 0.1)
				(type default)
			)
			(layer "F.Fab")
		)
		(fp_poly
			(pts
				(xy -0.761746 0) (xy -2.285746 -0.762) (xy -2.285746 0.762)
			)
			(stroke
				(width 0)
				(type default)
			)
			(fill yes)
			(layer "F.Fab")
		)
		(pad "1" thru_hole circle
			(at 0 0 270)
			(size 1.0033 1.0033)
			(drill 0.249936)
			(layers "*.Cu" "*.Mask")
			(remove_unused_layers no)
			(net "TDR_DIFF_85_IN2_DN")
			(clearance 0.10795)
			(thermal_gap 0.10795)
			(padstack
				(mode front_inner_back)
				(layer "Inner"
					(shape circle)
					(size 0.8001 0.8001)
					(clearance 0.1524)
				)
				(layer "B.Cu"
					(shape circle)
					(size 1.0033 1.0033)
					(clearance 0.10795)
				)
			)
		)
		(pad "2" thru_hole circle
			(at 2.54 0 270)
			(size 1.9939 1.9939)
			(drill 0.249936)
			(layers "*.Cu" "*.Mask")
			(remove_unused_layers no)
			(net "T1_GND")
			(clearance 0.10795)
			(thermal_gap 0.10795)
			(padstack
				(mode front_inner_back)
				(layer "Inner"
					(shape circle)
					(size 0.8001 0.8001)
					(clearance 0.1524)
				)
				(layer "B.Cu"
					(shape circle)
					(size 1.9939 1.9939)
					(clearance 0.10795)
				)
			)
		)
		(pad "3" thru_hole circle
			(at 2.54 2.54 270)
			(size 1.9939 1.9939)
			(drill 0.249936)
			(layers "*.Cu" "*.Mask")
			(remove_unused_layers no)
			(net "T1_GND")
			(clearance 0.10795)
			(thermal_gap 0.10795)
			(padstack
				(mode front_inner_back)
				(layer "Inner"
					(shape circle)
					(size 0.8001 0.8001)
					(clearance 0.1524)
				)
				(layer "B.Cu"
					(shape circle)
					(size 1.9939 1.9939)
					(clearance 0.10795)
				)
			)
		)
		(pad "4" thru_hole circle
			(at 0 2.54 270)
			(size 1.0033 1.0033)
			(drill 0.249936)
			(layers "*.Cu" "*.Mask")
			(remove_unused_layers no)
			(net "TDR_DIFF_85_IN2_DP")
			(clearance 0.10795)
			(thermal_gap 0.10795)
			(padstack
				(mode front_inner_back)
				(layer "Inner"
					(shape circle)
					(size 0.8001 0.8001)
					(clearance 0.1524)
				)
				(layer "B.Cu"
					(shape circle)
					(size 1.0033 1.0033)
					(clearance 0.10795)
				)
			)
		)
	)
	(footprint ""
		(layer "F.Cu")
		(at 258.37388 -50.565304)
		(property "Reference" "PR3944"
			(at 0 0 0)
			(layer "F.SilkS")
			(hide yes)
			(effects
				(font
					(size 1.27 1.27)
				)
			)
		)
		(property "Value" ""
			(at 0 0 0)
			(layer "F.Fab")
			(effects
				(font
					(size 1.27 1.27)
				)
			)
		)
		(duplicate_pad_numbers_are_jumpers no)
		(fp_line
			(start -0.7874 -0.4064)
			(end 0.7874 -0.4064)
			(stroke
				(width 0.1524)
				(type default)
			)
			(layer "F.SilkS")
		)
		(fp_line
			(start -0.7874 0.4064)
			(end -0.7874 -0.4064)
			(stroke
				(width 0.1524)
				(type default)
			)
			(layer "F.SilkS")
		)
		(fp_line
			(start 0.7874 -0.4064)
			(end 0.7874 0.4064)
			(stroke
				(width 0.1524)
				(type default)
			)
			(layer "F.SilkS")
		)
		(fp_line
			(start 0.7874 0.4064)
			(end -0.7874 0.4064)
			(stroke
				(width 0.1524)
				(type default)
			)
			(layer "F.SilkS")
		)
		(fp_line
			(start -0.67945 -0.305054)
			(end -0.12065 -0.305054)
			(stroke
				(width 0.1)
				(type default)
			)
			(layer "F.Fab")
		)
		(fp_line
			(start -0.67945 0.3048)
			(end -0.67945 -0.305054)
			(stroke
				(width 0.1)
				(type default)
			)
			(layer "F.Fab")
		)
		(fp_line
			(start -0.12065 -0.305054)
			(end -0.12065 -0.2794)
			(stroke
				(width 0.1)
				(type default)
			)
			(layer "F.Fab")
		)
		(fp_line
			(start -0.12065 -0.2794)
			(end 0.12065 -0.2794)
			(stroke
				(width 0.1)
				(type default)
			)
			(layer "F.Fab")
		)
		(fp_line
			(start -0.12065 0.2794)
			(end -0.12065 0.3048)
			(stroke
				(width 0.1)
				(type default)
			)
			(layer "F.Fab")
		)
		(fp_line
			(start -0.12065 0.3048)
			(end -0.67945 0.3048)
			(stroke
				(width 0.1)
				(type default)
			)
			(layer "F.Fab")
		)
		(fp_line
			(start 0.120396 0.2794)
			(end -0.12065 0.2794)
			(stroke
				(width 0.1)
				(type default)
			)
			(layer "F.Fab")
		)
		(fp_line
			(start 0.120396 0.3048)
			(end 0.120396 0.2794)
			(stroke
				(width 0.1)
				(type default)
			)
			(layer "F.Fab")
		)
		(fp_line
			(start 0.12065 -0.3048)
			(end 0.67945 -0.3048)
			(stroke
				(width 0.1)
				(type default)
			)
			(layer "F.Fab")
		)
		(fp_line
			(start 0.12065 -0.2794)
			(end 0.12065 -0.3048)
			(stroke
				(width 0.1)
				(type default)
			)
			(layer "F.Fab")
		)
		(fp_line
			(start 0.67945 -0.3048)
			(end 0.67945 0.3048)
			(stroke
				(width 0.1)
				(type default)
			)
			(layer "F.Fab")
		)
		(fp_line
			(start 0.67945 0.3048)
			(end 0.120396 0.3048)
			(stroke
				(width 0.1)
				(type default)
			)
			(layer "F.Fab")
		)
		(pad "1" smd circle
			(at -0.40005 0)
			(size 0 0)
			(layers "F.Cu" "F.Mask" "F.Paste")
			(net "P12V_E1S_ISET_0")
		)
		(pad "2" smd circle
			(at 0.40005 0)
			(size 0 0)
			(layers "F.Cu" "F.Mask" "F.Paste")
			(net "GND")
		)
	)
)
